# T6G (Grand Teton) — schematic netlist excerpt (pin names and nets, part order shuffled) for the footprints in the layout excerpt that follows; sources: Cadence DE-HDL packaged netlist, KiCad conversion of 04192023_DAF0TMB3IC0_F0TG_MB_C_brd_V02_OCP.brd

R3208  Q_RES  100 1% CHIP  pkg 0402LF  page 138 : A = OCP_V3_2_ISO_BIF0_EN ; B = GND
PR131  Q_RES  2.2 1% CHIP  pkg 0402LF  page 208 : A = PVDD11_S3_P0_PVCC ; B = PVDD11_S3_P0_VCC1

(kicad_pcb
	(version 20260206)
	(generator "pcbnew")
	(generator_version "10.0")
	(general
		(thickness 1.6)
		(legacy_teardrops no)
	)
	(paper "A4")
	(title_block
		(title "04192023_DAF0TMB3IC0_F0TG_MB_C_brd_V02_OCP.brd")
		(comment 1 "Grand Teton / footprints 7984-7985 of 8354")
	)
	(layers
		(0 "F.Cu" signal "TOP")
		(4 "In1.Cu" signal "GND")
		(6 "In2.Cu" signal "IN1")
		(8 "In3.Cu" signal "GND1")
		(10 "In4.Cu" signal "IN2")
		(12 "In5.Cu" signal "GND2")
		(14 "In6.Cu" signal "IN3")
		(16 "In7.Cu" signal "GND3")
		(18 "In8.Cu" signal "VCC")
		(20 "In9.Cu" signal "VCC1")
		(22 "In10.Cu" signal "GND4")
		(24 "In11.Cu" signal "IN4")
		(26 "In12.Cu" signal "GND5")
		(28 "In13.Cu" signal "IN5")
		(30 "In14.Cu" signal "GND6")
		(32 "In15.Cu" signal "IN6")
		(34 "In16.Cu" signal "GND7")
		(2 "B.Cu" signal "BOTTOM")
		(9 "F.Adhes" user "F.Adhesive")
		(11 "B.Adhes" user "B.Adhesive")
		(13 "F.Paste" user "Package Geometry/Pastemask Top")
		(15 "B.Paste" user "Package Geometry/Pastemask Bottom")
		(5 "F.SilkS" user "Ref Des/Silkscreen Top")
		(7 "B.SilkS" user "Ref Des/Silkscreen Bottom")
		(1 "F.Mask" user "Board Geometry/Soldermask Top")
		(3 "B.Mask" user "Board Geometry/Soldermask Bottom")
		(17 "Dwgs.User" user "User.Drawings")
		(19 "Cmts.User" user "User.Comments")
		(21 "Eco1.User" user "User.Eco1")
		(23 "Eco2.User" user "User.Eco2")
		(25 "Edge.Cuts" user "Board Geometry/Outline")
		(27 "Margin" user)
		(31 "F.CrtYd" user "Package Geometry/Place Bound Top")
		(29 "B.CrtYd" user "Package Geometry/Place Bound Bottom")
		(35 "F.Fab" user "Ref Des/Assembly Top")
		(33 "B.Fab" user "Ref Des/Assembly Bottom")
	)
	(footprint ""
		(layer "B.Cu")
		(at 62.68847 -15.58036 90)
		(property "Reference" "R3208"
			(at 0 0 90)
			(layer "B.SilkS")
			(hide yes)
			(effects
				(font
					(size 1.27 1.27)
				)
				(justify mirror)
			)
		)
		(property "Value" ""
			(at 0 0 90)
			(layer "B.Fab")
			(effects
				(font
					(size 1.27 1.27)
				)
				(justify mirror)
			)
		)
		(duplicate_pad_numbers_are_jumpers no)
		(fp_line
			(start 0.7874 -0.4064)
			(end -0.7874 -0.4064)
			(stroke
				(width 0.1524)
				(type default)
			)
			(layer "B.SilkS")
		)
		(fp_line
			(start -0.7874 -0.4064)
			(end -0.7874 0.4064)
			(stroke
				(width 0.1524)
				(type default)
			)
			(layer "B.SilkS")
		)
		(fp_line
			(start 0.7874 0.4064)
			(end 0.7874 -0.4064)
			(stroke
				(width 0.1524)
				(type default)
			)
			(layer "B.SilkS")
		)
		(fp_line
			(start -0.7874 0.4064)
			(end 0.7874 0.4064)
			(stroke
				(width 0.1524)
				(type default)
			)
			(layer "B.SilkS")
		)
		(fp_line
			(start 0.67945 -0.305054)
			(end 0.12065 -0.305054)
			(stroke
				(width 0.1)
				(type default)
			)
			(layer "B.Fab")
		)
		(fp_line
			(start 0.12065 -0.305054)
			(end 0.12065 -0.2794)
			(stroke
				(width 0.1)
				(type default)
			)
			(layer "B.Fab")
		)
		(fp_line
			(start -0.12065 -0.3048)
			(end -0.67945 -0.3048)
			(stroke
				(width 0.1)
				(type default)
			)
			(layer "B.Fab")
		)
		(fp_line
			(start -0.67945 -0.3048)
			(end -0.67945 0.3048)
			(stroke
				(width 0.1)
				(type default)
			)
			(layer "B.Fab")
		)
		(fp_line
			(start 0.12065 -0.2794)
			(end -0.12065 -0.2794)
			(stroke
				(width 0.1)
				(type default)
			)
			(layer "B.Fab")
		)
		(fp_line
			(start -0.12065 -0.2794)
			(end -0.12065 -0.3048)
			(stroke
				(width 0.1)
				(type default)
			)
			(layer "B.Fab")
		)
		(fp_line
			(start 0.12065 0.2794)
			(end 0.12065 0.3048)
			(stroke
				(width 0.1)
				(type default)
			)
			(layer "B.Fab")
		)
		(fp_line
			(start -0.120396 0.2794)
			(end 0.12065 0.2794)
			(stroke
				(width 0.1)
				(type default)
			)
			(layer "B.Fab")
		)
		(fp_line
			(start 0.67945 0.3048)
			(end 0.67945 -0.305054)
			(stroke
				(width 0.1)
				(type default)
			)
			(layer "B.Fab")
		)
		(fp_line
			(start 0.12065 0.3048)
			(end 0.67945 0.3048)
			(stroke
				(width 0.1)
				(type default)
			)
			(layer "B.Fab")
		)
		(fp_line
			(start -0.120396 0.3048)
			(end -0.120396 0.2794)
			(stroke
				(width 0.1)
				(type default)
			)
			(layer "B.Fab")
		)
		(fp_line
			(start -0.67945 0.3048)
			(end -0.120396 0.3048)
			(stroke
				(width 0.1)
				(type default)
			)
			(layer "B.Fab")
		)
		(pad "1" smd circle
			(at 0.40005 0 270)
			(size 0 0)
			(layers "B.Cu" "B.Mask" "B.Paste")
			(net "OCP_V3_2_ISO_BIF0_EN")
		)
		(pad "2" smd circle
			(at -0.40005 0 270)
			(size 0 0)
			(layers "B.Cu" "B.Mask" "B.Paste")
			(net "GND")
		)
	)
	(footprint ""
		(layer "B.Cu")
		(at 421.333168 -352.174048 -90)
		(property "Reference" "PR131"
			(at 0 0 90)
			(layer "B.SilkS")
			(hide yes)
			(effects
				(font
					(size 1.27 1.27)
				)
				(justify mirror)
			)
		)
		(property "Value" ""
			(at 0 0 90)
			(layer "B.Fab")
			(effects
				(font
					(size 1.27 1.27)
				)
				(justify mirror)
			)
		)
		(duplicate_pad_numbers_are_jumpers no)
		(fp_line
			(start -0.7874 0.4064)
			(end 0.7874 0.4064)
			(stroke
				(width 0.1524)
				(type default)
			)
			(layer "B.SilkS")
		)
		(fp_line
			(start 0.7874 0.4064)
			(end 0.7874 -0.4064)
			(stroke
				(width 0.1524)
				(type default)
			)
			(layer "B.SilkS")
		)
		(fp_line
			(start -0.7874 -0.4064)
			(end -0.7874 0.4064)
			(stroke
				(width 0.1524)
				(type default)
			)
			(layer "B.SilkS")
		)
		(fp_line
			(start 0.7874 -0.4064)
			(end -0.7874 -0.4064)
			(stroke
				(width 0.1524)
				(type default)
			)
			(layer "B.SilkS")
		)
		(fp_line
			(start -0.67945 0.3048)
			(end -0.120396 0.3048)
			(stroke
				(width 0.1)
				(type default)
			)
			(layer "B.Fab")
		)
		(fp_line
			(start -0.120396 0.3048)
			(end -0.120396 0.2794)
			(stroke
				(width 0.1)
				(type default)
			)
			(layer "B.Fab")
		)
		(fp_line
			(start 0.12065 0.3048)
			(end 0.67945 0.3048)
			(stroke
				(width 0.1)
				(type default)
			)
			(layer "B.Fab")
		)
		(fp_line
			(start 0.67945 0.3048)
			(end 0.67945 -0.305054)
			(stroke
				(width 0.1)
				(type default)
			)
			(layer "B.Fab")
		)
		(fp_line
			(start -0.120396 0.2794)
			(end 0.12065 0.2794)
			(stroke
				(width 0.1)
				(type default)
			)
			(layer "B.Fab")
		)
		(fp_line
			(start 0.12065 0.2794)
			(end 0.12065 0.3048)
			(stroke
				(width 0.1)
				(type default)
			)
			(layer "B.Fab")
		)
		(fp_line
			(start -0.12065 -0.2794)
			(end -0.12065 -0.3048)
			(stroke
				(width 0.1)
				(type default)
			)
			(layer "B.Fab")
		)
		(fp_line
			(start 0.12065 -0.2794)
			(end -0.12065 -0.2794)
			(stroke
				(width 0.1)
				(type default)
			)
			(layer "B.Fab")
		)
		(fp_line
			(start -0.67945 -0.3048)
			(end -0.67945 0.3048)
			(stroke
				(width 0.1)
				(type default)
			)
			(layer "B.Fab")
		)
		(fp_line
			(start -0.12065 -0.3048)
			(end -0.67945 -0.3048)
			(stroke
				(width 0.1)
				(type default)
			)
			(layer "B.Fab")
		)
		(fp_line
			(start 0.12065 -0.305054)
			(end 0.12065 -0.2794)
			(stroke
				(width 0.1)
				(type default)
			)
			(layer "B.Fab")
		)
		(fp_line
			(start 0.67945 -0.305054)
			(end 0.12065 -0.305054)
			(stroke
				(width 0.1)
				(type default)
			)
			(layer "B.Fab")
		)
		(pad "1" smd circle
			(at 0.40005 0 90)
			(size 0 0)
			(layers "B.Cu" "B.Mask" "B.Paste")
			(net "PVDD11_S3_P0_PVCC")
		)
		(pad "2" smd circle
			(at -0.40005 0 90)
			(size 0 0)
			(layers "B.Cu" "B.Mask" "B.Paste")
			(net "PVDD11_S3_P0_VCC1")
		)
	)
)
